# T6G (Grand Teton) — schematic netlist excerpt (pin names and nets, part order shuffled) for the footprints in the layout excerpt that follows; sources: Cadence DE-HDL packaged netlist, KiCad conversion of 04192023_DAF0TMB3IC0_F0TG_MB_C_brd_V02_OCP.brd

C619  Q_CAP  0.1UF 10V 10% X7S  pkg C0201  page 290 : A = P0V9_CPU0_RT_2D ; B = GND
R8282  Q_RES  0 5% CHIP  pkg 0402LF  page 193 : A = PVDDCR_SOC_P0_EN ; B = PVDDCR_SOC_P0_EN_RC
C800  Q_CAP  0.1UF 10V 10% X7S  pkg C0201  page 301 : A = P0V9_CPU0_RT2_2A ; B = GND

(kicad_pcb
	(version 20260206)
	(generator "pcbnew")
	(generator_version "10.0")
	(general
		(thickness 1.6)
		(legacy_teardrops no)
	)
	(paper "A4")
	(title_block
		(title "04192023_DAF0TMB3IC0_F0TG_MB_C_brd_V02_OCP.brd")
		(comment 1 "Grand Teton / footprints 7188-7190 of 8354")
	)
	(layers
		(0 "F.Cu" signal "TOP")
		(4 "In1.Cu" signal "GND")
		(6 "In2.Cu" signal "IN1")
		(8 "In3.Cu" signal "GND1")
		(10 "In4.Cu" signal "IN2")
		(12 "In5.Cu" signal "GND2")
		(14 "In6.Cu" signal "IN3")
		(16 "In7.Cu" signal "GND3")
		(18 "In8.Cu" signal "VCC")
		(20 "In9.Cu" signal "VCC1")
		(22 "In10.Cu" signal "GND4")
		(24 "In11.Cu" signal "IN4")
		(26 "In12.Cu" signal "GND5")
		(28 "In13.Cu" signal "IN5")
		(30 "In14.Cu" signal "GND6")
		(32 "In15.Cu" signal "IN6")
		(34 "In16.Cu" signal "GND7")
		(2 "B.Cu" signal "BOTTOM")
		(9 "F.Adhes" user "F.Adhesive")
		(11 "B.Adhes" user "B.Adhesive")
		(13 "F.Paste" user "Package Geometry/Pastemask Top")
		(15 "B.Paste" user "Package Geometry/Pastemask Bottom")
		(5 "F.SilkS" user "Ref Des/Silkscreen Top")
		(7 "B.SilkS" user "Ref Des/Silkscreen Bottom")
		(1 "F.Mask" user "Board Geometry/Soldermask Top")
		(3 "B.Mask" user "Board Geometry/Soldermask Bottom")
		(17 "Dwgs.User" user "User.Drawings")
		(19 "Cmts.User" user "User.Comments")
		(21 "Eco1.User" user "User.Eco1")
		(23 "Eco2.User" user "User.Eco2")
		(25 "Edge.Cuts" user "Board Geometry/Outline")
		(27 "Margin" user)
		(31 "F.CrtYd" user "Package Geometry/Place Bound Top")
		(29 "B.CrtYd" user "Package Geometry/Place Bound Bottom")
		(35 "F.Fab" user "Ref Des/Assembly Top")
		(33 "B.Fab" user "Ref Des/Assembly Bottom")
	)
	(footprint ""
		(layer "B.Cu")
		(at 404.346156 -396.393162 -90)
		(property "Reference" "C800"
			(at 0 0 90)
			(layer "B.SilkS")
			(hide yes)
			(effects
				(font
					(size 1.27 1.27)
				)
				(justify mirror)
			)
		)
		(property "Value" ""
			(at 0 0 90)
			(layer "B.Fab")
			(effects
				(font
					(size 1.27 1.27)
				)
				(justify mirror)
			)
		)
		(duplicate_pad_numbers_are_jumpers no)
		(fp_line
			(start -0.299974 0.150114)
			(end 0.299974 0.150114)
			(stroke
				(width 0.1)
				(type default)
			)
			(layer "B.Fab")
		)
		(fp_line
			(start 0.299974 0.150114)
			(end 0.299974 -0.150114)
			(stroke
				(width 0.1)
				(type default)
			)
			(layer "B.Fab")
		)
		(fp_line
			(start -0.299974 -0.150114)
			(end -0.299974 0.150114)
			(stroke
				(width 0.1)
				(type default)
			)
			(layer "B.Fab")
		)
		(fp_line
			(start 0.299974 -0.150114)
			(end -0.299974 -0.150114)
			(stroke
				(width 0.1)
				(type default)
			)
			(layer "B.Fab")
		)
		(pad "1" smd rect
			(at 0.2667 0 90)
			(size 0.3048 0.381)
			(layers "B.Cu" "B.Mask" "B.Paste")
			(net "P0V9_CPU0_RT2_2A")
		)
		(pad "2" smd rect
			(at -0.2667 0 90)
			(size 0.3048 0.381)
			(layers "B.Cu" "B.Mask" "B.Paste")
			(net "GND")
		)
	)
	(footprint ""
		(layer "B.Cu")
		(at 347.906086 -395.148562 90)
		(property "Reference" "C619"
			(at 0 0 90)
			(layer "B.SilkS")
			(hide yes)
			(effects
				(font
					(size 1.27 1.27)
				)
				(justify mirror)
			)
		)
		(property "Value" ""
			(at 0 0 90)
			(layer "B.Fab")
			(effects
				(font
					(size 1.27 1.27)
				)
				(justify mirror)
			)
		)
		(duplicate_pad_numbers_are_jumpers no)
		(fp_line
			(start 0.299974 -0.150114)
			(end -0.299974 -0.150114)
			(stroke
				(width 0.1)
				(type default)
			)
			(layer "B.Fab")
		)
		(fp_line
			(start -0.299974 -0.150114)
			(end -0.299974 0.150114)
			(stroke
				(width 0.1)
				(type default)
			)
			(layer "B.Fab")
		)
		(fp_line
			(start 0.299974 0.150114)
			(end 0.299974 -0.150114)
			(stroke
				(width 0.1)
				(type default)
			)
			(layer "B.Fab")
		)
		(fp_line
			(start -0.299974 0.150114)
			(end 0.299974 0.150114)
			(stroke
				(width 0.1)
				(type default)
			)
			(layer "B.Fab")
		)
		(pad "1" smd rect
			(at 0.2667 0 270)
			(size 0.3048 0.381)
			(layers "B.Cu" "B.Mask" "B.Paste")
			(net "P0V9_CPU0_RT_2D")
		)
		(pad "2" smd rect
			(at -0.2667 0 270)
			(size 0.3048 0.381)
			(layers "B.Cu" "B.Mask" "B.Paste")
			(net "GND")
		)
	)
	(footprint ""
		(layer "B.Cu")
		(at 367.671858 -134.954772 180)
		(property "Reference" "R8282"
			(at 0 0 0)
			(layer "B.SilkS")
			(hide yes)
			(effects
				(font
					(size 1.27 1.27)
				)
				(justify mirror)
			)
		)
		(property "Value" ""
			(at 0 0 0)
			(layer "B.Fab")
			(effects
				(font
					(size 1.27 1.27)
				)
				(justify mirror)
			)
		)
		(duplicate_pad_numbers_are_jumpers no)
		(fp_line
			(start 0.7874 0.4064)
			(end 0.7874 -0.4064)
			(stroke
				(width 0.1524)
				(type default)
			)
			(layer "B.SilkS")
		)
		(fp_line
			(start 0.7874 -0.4064)
			(end -0.7874 -0.4064)
			(stroke
				(width 0.1524)
				(type default)
			)
			(layer "B.SilkS")
		)
		(fp_line
			(start -0.7874 0.4064)
			(end 0.7874 0.4064)
			(stroke
				(width 0.1524)
				(type default)
			)
			(layer "B.SilkS")
		)
		(fp_line
			(start -0.7874 -0.4064)
			(end -0.7874 0.4064)
			(stroke
				(width 0.1524)
				(type default)
			)
			(layer "B.SilkS")
		)
		(fp_line
			(start 0.67945 0.3048)
			(end 0.67945 -0.305054)
			(stroke
				(width 0.1)
				(type default)
			)
			(layer "B.Fab")
		)
		(fp_line
			(start 0.67945 -0.305054)
			(end 0.12065 -0.305054)
			(stroke
				(width 0.1)
				(type default)
			)
			(layer "B.Fab")
		)
		(fp_line
			(start 0.12065 0.3048)
			(end 0.67945 0.3048)
			(stroke
				(width 0.1)
				(type default)
			)
			(layer "B.Fab")
		)
		(fp_line
			(start 0.12065 0.2794)
			(end 0.12065 0.3048)
			(stroke
				(width 0.1)
				(type default)
			)
			(layer "B.Fab")
		)
		(fp_line
			(start 0.12065 -0.2794)
			(end -0.12065 -0.2794)
			(stroke
				(width 0.1)
				(type default)
			)
			(layer "B.Fab")
		)
		(fp_line
			(start 0.12065 -0.305054)
			(end 0.12065 -0.2794)
			(stroke
				(width 0.1)
				(type default)
			)
			(layer "B.Fab")
		)
		(fp_line
			(start -0.120396 0.3048)
			(end -0.120396 0.2794)
			(stroke
				(width 0.1)
				(type default)
			)
			(layer "B.Fab")
		)
		(fp_line
			(start -0.120396 0.2794)
			(end 0.12065 0.2794)
			(stroke
				(width 0.1)
				(type default)
			)
			(layer "B.Fab")
		)
		(fp_line
			(start -0.12065 -0.2794)
			(end -0.12065 -0.3048)
			(stroke
				(width 0.1)
				(type default)
			)
			(layer "B.Fab")
		)
		(fp_line
			(start -0.12065 -0.3048)
			(end -0.67945 -0.3048)
			(stroke
				(width 0.1)
				(type default)
			)
			(layer "B.Fab")
		)
		(fp_line
			(start -0.67945 0.3048)
			(end -0.120396 0.3048)
			(stroke
				(width 0.1)
				(type default)
			)
			(layer "B.Fab")
		)
		(fp_line
			(start -0.67945 -0.3048)
			(end -0.67945 0.3048)
			(stroke
				(width 0.1)
				(type default)
			)
			(layer "B.Fab")
		)
		(pad "1" smd circle
			(at 0.40005 0)
			(size 0 0)
			(layers "B.Cu" "B.Mask" "B.Paste")
			(net "PVDDCR_SOC_P0_EN")
		)
		(pad "2" smd circle
			(at -0.40005 0)
			(size 0 0)
			(layers "B.Cu" "B.Mask" "B.Paste")
			(net "PVDDCR_SOC_P0_EN_RC")
		)
	)
)
